# T6G (Grand Teton) — schematic netlist excerpt (pin names and nets, part order shuffled) for the footprints in the layout excerpt that follows; sources: Cadence DE-HDL packaged netlist, KiCad conversion of 04192023_DAF0TMB3IC0_F0TG_MB_C_brd_V02_OCP.brd

J67  SCONN288_DDR506112002KQ  IO  pkg DDR288S_1-1VXC  page 97
  VIN_BULK0  = P12V_MEM_CPU0
  RFU0  = NC
  VIN_MGMT  = P3V3_AUX
  HSCL  = I3C_SPD_DDRL_CPU0_SCL
  HSDA  = I3C_SPD_DDRL_CPU0_SDA
  VSS0  = GND
  DQ0_A  = M_L_CPU0_SA_DQ<0>
  VSS1  = GND
  DQ1_A  = M_L_CPU0_SA_DQ<1>
  VSS2  = GND
  DQS0_A_T  = M_L_CPU0_SA_DQS_DP<0>
  DQS0_A_C  = M_L_CPU0_SA_DQS_DN<0>
  VSS3  = GND
  DQ4_A  = M_L_CPU0_SA_DQ<4>
  VSS4  = GND
  DQ5_A  = M_L_CPU0_SA_DQ<5>
  VSS5  = GND
  DQ8_A  = M_L_CPU0_SA_DQ<8>
  VSS6  = GND
  DQ9_A  = M_L_CPU0_SA_DQ<9>
  VSS7  = GND
  DQS1_A_T  = M_L_CPU0_SA_DQS_DP<1>
  DQS1_A_C  = M_L_CPU0_SA_DQS_DN<1>
  VSS8  = GND
  DQ12_A  = M_L_CPU0_SA_DQ<12>
  VSS9  = GND
  DQ13_A  = M_L_CPU0_SA_DQ<13>
  VSS10  = GND
  DQ16_A  = M_L_CPU0_SA_DQ<16>
  VSS11  = GND
  DQ17_A  = M_L_CPU0_SA_DQ<17>
  VSS12  = GND
  DQS2_A_T  = M_L_CPU0_SA_DQS_DP<2>
  DQS2_A_C  = M_L_CPU0_SA_DQS_DN<2>
  VSS13  = GND
  DQ20_A  = M_L_CPU0_SA_DQ<20>
  VSS14  = GND
  DQ21_A  = M_L_CPU0_SA_DQ<21>
  VSS15  = GND
  DQ24_A  = M_L_CPU0_SA_DQ<24>
  VSS16  = GND
  DQ25_A  = M_L_CPU0_SA_DQ<25>
  VSS17  = GND
  DQS3_A_T  = M_L_CPU0_SA_DQS_DP<3>
  DQS3_A_C  = M_L_CPU0_SA_DQS_DN<3>
  VSS18  = GND
  DQ28_A  = M_L_CPU0_SA_DQ<28>
  VSS19  = GND
  DQ29_A  = M_L_CPU0_SA_DQ<29>
  VSS20  = GND
  CB0_A  = M_L_CPU0_SA_CB<0>
  VSS21  = GND
  CB1_A  = M_L_CPU0_SA_CB<1>
  VSS22  = GND
  DQS4_A_T  = M_L_CPU0_SA_DQS_DP<4>
  DQS4_A_C  = M_L_CPU0_SA_DQS_DN<4>
  VSS23  = GND
  CB4_A  = M_L_CPU0_SA_CB<4>
  VSS24  = GND
  CB5_A  = M_L_CPU0_SA_CB<5>
  VSS25  = GND
  ALERT_N  = M_L_CPU0_ALERT_N
  VSS26  = GND
  CS0_A_N  = M_L_CPU0_SA_CS_N<0>
  VSS27  = GND
  CA0_A  = M_L_CPU0_SA_CA<0>
  VSS28  = GND
  CA2_A  = M_L_CPU0_SA_CA<2>
  VSS29  = GND
  CA4_A  = M_L_CPU0_SA_CA<4>
  VSS30  = GND
  CA6_A  = M_L_CPU0_SA_CA<6>
  VSS31  = GND
  PAR_A  = M_L_CPU0_SA_PAR
  VSS32  = GND
  CA0_B  = M_L_CPU0_SB_CA<0>
  VSS33  = GND
  CA2_B  = M_L_CPU0_SB_CA<2>
  VSS34  = GND
  CA4_B  = M_L_CPU0_SB_CA<4>
  VSS35  = GND
  CA6_B  = M_L_CPU0_SB_CA<6>
  VSS36  = GND
  CS0_B_N  = M_L_CPU0_SB_CS_N<0>
  VSS37  = GND
  \lbd||rsp_a_n\  = M_L_CPU0_SA_RSP<0>
  \lbs||rsp_b_n\  = M_L_CPU0_SB_RSP<0>
  VSS38  = GND
  CB4_B  = M_L_CPU0_SB_CB<4>
  VSS39  = GND
  CB5_B  = M_L_CPU0_SB_CB<5>
  VSS40  = GND
  \dqs9_b_t||tdqs9_b_t||dbi4_b_n\  = M_L_CPU0_SB_DQS_DP<9>
  \dqs9_b_c||tdqs9_b_c\  = M_L_CPU0_SB_DQS_DN<9>
  VSS41  = GND
  CB0_B  = M_L_CPU0_SB_CB<0>
  VSS42  = GND
  CB1_B  = M_L_CPU0_SB_CB<1>
  VSS43  = GND
  DQ0_B  = M_L_CPU0_SB_DQ<0>
  VSS44  = GND
  DQ1_B  = M_L_CPU0_SB_DQ<1>
  VSS45  = GND
  DQS0_B_T  = M_L_CPU0_SB_DQS_DP<0>
  DQS0_B_C  = M_L_CPU0_SB_DQS_DN<0>
  VSS46  = GND
  DQ4_B  = M_L_CPU0_SB_DQ<4>
  VSS47  = GND
  DQ5_B  = M_L_CPU0_SB_DQ<5>
  VSS48  = GND
  DQ8_B  = M_L_CPU0_SB_DQ<8>
  VSS49  = GND
  DQ9_B  = M_L_CPU0_SB_DQ<9>
  VSS50  = GND
  DQS1_B_T  = M_L_CPU0_SB_DQS_DP<1>
  DQS1_B_C  = M_L_CPU0_SB_DQS_DN<1>
  VSS51  = GND
  DQ12_B  = M_L_CPU0_SB_DQ<12>
  VSS52  = GND
  DQ13_B  = M_L_CPU0_SB_DQ<13>
  VSS53  = GND
  DQ16_B  = M_L_CPU0_SB_DQ<16>
  VSS54  = GND
  DQ17_B  = M_L_CPU0_SB_DQ<17>
  VSS55  = GND
  DQS2_B_T  = M_L_CPU0_SB_DQS_DP<2>
  DQS2_B_C  = M_L_CPU0_SB_DQS_DN<2>
  VSS56  = GND
  DQ20_B  = M_L_CPU0_SB_DQ<20>
  VSS57  = GND
  DQ21_B  = M_L_CPU0_SB_DQ<21>
  VSS58  = GND
  DQ24_B  = M_L_CPU0_SB_DQ<24>
  VSS59  = GND
  DQ25_B  = M_L_CPU0_SB_DQ<25>
  VSS60  = GND
  DQS3_B_T  = M_L_CPU0_SB_DQS_DP<3>
  DQS3_B_C  = M_L_CPU0_SB_DQS_DN<3>
  VSS61  = GND
  DQ28_B  = M_L_CPU0_SB_DQ<28>
  VSS62  = GND
  DQ29_B  = M_L_CPU0_SB_DQ<29>
  VSS63  = GND
  RFU1  = NC
  VIN_BULK1  = P12V_MEM_CPU0
  VIN_BULK2  = P12V_MEM_CPU0
  \pwr_good||fail_n\  = PWRGD_CHL_CPU0_DIMM
  HAS  = PD_CHL_CPU0_DIMM_SAA
  RFU2  = NC
  RFU3  = NC
  VSS64  = GND
  DQ2_A  = M_L_CPU0_SA_DQ<2>
  VSS65  = GND
  DQ3_A  = M_L_CPU0_SA_DQ<3>
  VSS66  = GND
  \dqs5_a_c||tdqs5_a_c||dqs5_a_t||tdqs5_a_t\  = M_L_CPU0_SA_DQS_DN<5>
  \dqs5_a_t||tdqs5_a_t\  = M_L_CPU0_SA_DQS_DP<5>
  VSS67  = GND
  DQ6_A  = M_L_CPU0_SA_DQ<6>
  VSS68  = GND
  DQ7_A  = M_L_CPU0_SA_DQ<7>
  VSS69  = GND
  DQ10_A  = M_L_CPU0_SA_DQ<10>
  VSS70  = GND
  DQ11_A  = M_L_CPU0_SA_DQ<11>
  VSS71  = GND
  \dqs6_a_c||tdqs6_a_c||dqs6_a_t||tdqs6_a_t\  = M_L_CPU0_SA_DQS_DN<6>
  \dqs6_a_t||tdqs6_a_t\  = M_L_CPU0_SA_DQS_DP<6>
  VSS72  = GND
  DQ14_A  = M_L_CPU0_SA_DQ<14>
  VSS73  = GND
  DQ15_A  = M_L_CPU0_SA_DQ<15>
  VSS74  = GND
  DQ18_A  = M_L_CPU0_SA_DQ<18>
  VSS75  = GND
  DQ19_A  = M_L_CPU0_SA_DQ<19>
  VSS76  = GND
  \dqs7_a_c||tdqs7_a_c\  = M_L_CPU0_SA_DQS_DN<7>
  \dqs7_a_t||tdqs7_a_t\  = M_L_CPU0_SA_DQS_DP<7>
  VSS77  = GND
  DQ22_A  = M_L_CPU0_SA_DQ<22>
  VSS78  = GND
  DQ23_A  = M_L_CPU0_SA_DQ<23>
  VSS79  = GND
  DQ26_A  = M_L_CPU0_SA_DQ<26>
  VSS80  = GND
  DQ27_A  = M_L_CPU0_SA_DQ<27>
  VSS81  = GND
  \dqs8_a_c||tdqs8_a_c\  = M_L_CPU0_SA_DQS_DN<8>
  \dqs8_a_t||tdqs8_a_t\  = M_L_CPU0_SA_DQS_DP<8>
  VSS82  = GND
  DQ30_A  = M_L_CPU0_SA_DQ<30>
  VSS83  = GND
  DQ31_A  = M_L_CPU0_SA_DQ<31>
  VSS84  = GND
  CB2_A  = M_L_CPU0_SA_CB<2>
  VSS85  = GND
  CB3_A  = M_L_CPU0_SA_CB<3>
  VSS86  = GND
  \dqs9_a_c||tdqs9_a_c\  = M_L_CPU0_SA_DQS_DN<9>
  \dqs9_a_t||tdqs9_a_t\  = M_L_CPU0_SA_DQS_DP<9>
  VSS87  = GND
  CB6_A  = M_L_CPU0_SA_CB<6>
  VSS88  = GND
  CB7_A  = M_L_CPU0_SA_CB<7>
  VSS89  = GND
  RESET_N  = M_L_CPU0_RESET_N
  VSS90  = GND
  CS1_A_N  = M_L_CPU0_SA_CS_N<1>
  VSS91  = GND
  CA1_A  = M_L_CPU0_SA_CA<1>
  VSS92  = GND
  CA3_A  = M_L_CPU0_SA_CA<3>
  VSS93  = GND
  CA5_A  = M_L_CPU0_SA_CA<5>
  VSS94  = GND
  CK_T  = M_L_CPU0_CLK_DP<0>
  CK_C  = M_L_CPU0_CLK_DN<0>
  VSS95  = GND
  RFU4  = NC
  CA1_B  = M_L_CPU0_SB_CA<1>
  VSS96  = GND
  CA3_B  = M_L_CPU0_SB_CA<3>
  VSS97  = GND
  CA5_B  = M_L_CPU0_SB_CA<5>
  VSS98  = GND
  PAR_B  = M_L_CPU0_SB_PAR
  VSS99  = GND
  CS1_B_N  = M_L_CPU0_SB_CS_N<1>
  VSS100  = GND
  RFU5  = NC
  RFU6  = NC
  VSS101  = GND
  CB6_B  = M_L_CPU0_SB_CB<6>
  VSS102  = GND
  CB7_B  = M_L_CPU0_SB_CB<7>
  VSS103  = GND
  DQS4_B_C  = M_L_CPU0_SB_DQS_DN<4>
  DQS4_B_T  = M_L_CPU0_SB_DQS_DP<4>
  VSS104  = GND
  CB2_B  = M_L_CPU0_SB_CB<2>
  VSS105  = GND
  CB3_B  = M_L_CPU0_SB_CB<3>
  VSS106  = GND
  DQ2_B  = M_L_CPU0_SB_DQ<2>
  VSS107  = GND
  DQ3_B  = M_L_CPU0_SB_DQ<3>
  VSS108  = GND
  \dqs5_b_c||tdqs5_b_c\  = M_L_CPU0_SB_DQS_DN<5>
  \dqs5_b_t||tdqs5_b_t\  = M_L_CPU0_SB_DQS_DP<5>
  VSS109  = GND
  DQ6_B  = M_L_CPU0_SB_DQ<6>
  VSS110  = GND
  DQ7_B  = M_L_CPU0_SB_DQ<7>
  VSS111  = GND
  DQ10_B  = M_L_CPU0_SB_DQ<10>
  VSS112  = GND
  DQ11_B  = M_L_CPU0_SB_DQ<11>
  VSS113  = GND
  \dqs6_b_c||tdqs6_b_c\  = M_L_CPU0_SB_DQS_DN<6>
  \dqs6_b_t||tdqs6_b_t\  = M_L_CPU0_SB_DQS_DP<6>
  VSS114  = GND
  DQ14_B  = M_L_CPU0_SB_DQ<14>
  VSS115  = GND
  DQ15_B  = M_L_CPU0_SB_DQ<15>
  VSS116  = GND
  DQ18_B  = M_L_CPU0_SB_DQ<18>
  VSS117  = GND
  DQ19_B  = M_L_CPU0_SB_DQ<19>
  VSS118  = GND
  \dqs7_b_c||tdqs7_b_c\  = M_L_CPU0_SB_DQS_DN<7>
  \dqs7_b_t||tdqs7_b_t\  = M_L_CPU0_SB_DQS_DP<7>
  VSS119  = GND
  DQ22_B  = M_L_CPU0_SB_DQ<22>
  VSS120  = GND
  DQ23_B  = M_L_CPU0_SB_DQ<23>
  VSS121  = GND
  DQ26_B  = M_L_CPU0_SB_DQ<26>
  VSS122  = GND
  DQ27_B  = M_L_CPU0_SB_DQ<27>
  VSS123  = GND
  \dqs8_b_c||tdqs8_b_c\  = M_L_CPU0_SB_DQS_DN<8>
  \dqs8_b_t||tdqs8_b_t\  = M_L_CPU0_SB_DQS_DP<8>
  VSS124  = GND
  DQ30_B  = M_L_CPU0_SB_DQ<30>
  VSS125  = GND
  DQ31_B  = M_L_CPU0_SB_DQ<31>
  VSS126  = GND
  G1  = GND
  G2  = GND
  G3  = GND

(kicad_pcb
	(version 20260206)
	(generator "pcbnew")
	(generator_version "10.0")
	(general
		(thickness 1.6)
		(legacy_teardrops no)
	)
	(paper "A4")
	(title_block
		(title "04192023_DAF0TMB3IC0_F0TG_MB_C_brd_V02_OCP.brd")
		(comment 1 "Grand Teton / footprint 3721 of 8354 (J67), pads 231-276 of 291")
	)
	(layers
		(0 "F.Cu" signal "TOP")
		(4 "In1.Cu" signal "GND")
		(6 "In2.Cu" signal "IN1")
		(8 "In3.Cu" signal "GND1")
		(10 "In4.Cu" signal "IN2")
		(12 "In5.Cu" signal "GND2")
		(14 "In6.Cu" signal "IN3")
		(16 "In7.Cu" signal "GND3")
		(18 "In8.Cu" signal "VCC")
		(20 "In9.Cu" signal "VCC1")
		(22 "In10.Cu" signal "GND4")
		(24 "In11.Cu" signal "IN4")
		(26 "In12.Cu" signal "GND5")
		(28 "In13.Cu" signal "IN5")
		(30 "In14.Cu" signal "GND6")
		(32 "In15.Cu" signal "IN6")
		(34 "In16.Cu" signal "GND7")
		(2 "B.Cu" signal "BOTTOM")
		(9 "F.Adhes" user "F.Adhesive")
		(11 "B.Adhes" user "B.Adhesive")
		(13 "F.Paste" user "Package Geometry/Pastemask Top")
		(15 "B.Paste" user "Package Geometry/Pastemask Bottom")
		(5 "F.SilkS" user "Ref Des/Silkscreen Top")
		(7 "B.SilkS" user "Ref Des/Silkscreen Bottom")
		(1 "F.Mask" user "Board Geometry/Soldermask Top")
		(3 "B.Mask" user "Board Geometry/Soldermask Bottom")
		(17 "Dwgs.User" user "User.Drawings")
		(19 "Cmts.User" user "User.Comments")
		(21 "Eco1.User" user "User.Eco1")
		(23 "Eco2.User" user "User.Eco2")
		(25 "Edge.Cuts" user "Board Geometry/Outline")
		(27 "Margin" user)
		(31 "F.CrtYd" user "Package Geometry/Place Bound Top")
		(29 "B.CrtYd" user "Package Geometry/Place Bound Bottom")
		(35 "F.Fab" user "Ref Des/Assembly Top")
		(33 "B.Fab" user "Ref Des/Assembly Bottom")
	)
	(footprint ""
		(layer "F.Cu")
		(at 452.138034 -255.560068 180)
		(property "Reference" "J67"
			(at 2.380488 -81.709768 0)
			(unlocked yes)
			(layer "F.SilkS")
			(effects
				(font
					(size 0.7874 0.5842)
					(thickness 0.1524)
				)
			)
		)
		(property "Value" ""
			(at 0 0 180)
			(layer "F.Fab")
			(effects
				(font
					(size 1.27 1.27)
				)
			)
		)
		(duplicate_pad_numbers_are_jumpers no)
		(pad "231" smd rect
			(at 2.050034 14.875002 90)
			(size 0.519938 1.4986)
			(layers "F.Cu" "F.Mask" "F.Paste")
			(net "Net_2408")
		)
		(pad "232" smd rect
			(at 2.050034 15.724886 90)
			(size 0.519938 1.4986)
			(layers "F.Cu" "F.Mask" "F.Paste")
			(net "Net_2409")
		)
		(pad "233" smd rect
			(at 2.050034 16.575024 90)
			(size 0.519938 1.4986)
			(layers "F.Cu" "F.Mask" "F.Paste")
			(net "GND")
		)
		(pad "234" smd rect
			(at 2.050034 17.424908 90)
			(size 0.519938 1.4986)
			(layers "F.Cu" "F.Mask" "F.Paste")
			(net "M_L_CPU0_SB_CB<6>")
		)
		(pad "235" smd rect
			(at 2.050034 18.275046 90)
			(size 0.519938 1.4986)
			(layers "F.Cu" "F.Mask" "F.Paste")
			(net "GND")
		)
		(pad "236" smd rect
			(at 2.050034 19.12493 90)
			(size 0.519938 1.4986)
			(layers "F.Cu" "F.Mask" "F.Paste")
			(net "M_L_CPU0_SB_CB<7>")
		)
		(pad "237" smd rect
			(at 2.050034 19.975068 90)
			(size 0.519938 1.4986)
			(layers "F.Cu" "F.Mask" "F.Paste")
			(net "GND")
		)
		(pad "238" smd rect
			(at 2.050034 20.824952 90)
			(size 0.519938 1.4986)
			(layers "F.Cu" "F.Mask" "F.Paste")
			(net "M_L_CPU0_SB_DQS_DN<4>")
		)
		(pad "239" smd rect
			(at 2.050034 21.67509 90)
			(size 0.519938 1.4986)
			(layers "F.Cu" "F.Mask" "F.Paste")
			(net "M_L_CPU0_SB_DQS_DP<4>")
		)
		(pad "240" smd rect
			(at 2.050034 22.524974 90)
			(size 0.519938 1.4986)
			(layers "F.Cu" "F.Mask" "F.Paste")
			(net "GND")
		)
		(pad "241" smd rect
			(at 2.050034 23.375112 90)
			(size 0.519938 1.4986)
			(layers "F.Cu" "F.Mask" "F.Paste")
			(net "M_L_CPU0_SB_CB<2>")
		)
		(pad "242" smd rect
			(at 2.050034 24.224996 90)
			(size 0.519938 1.4986)
			(layers "F.Cu" "F.Mask" "F.Paste")
			(net "GND")
		)
		(pad "243" smd rect
			(at 2.050034 25.07488 90)
			(size 0.519938 1.4986)
			(layers "F.Cu" "F.Mask" "F.Paste")
			(net "M_L_CPU0_SB_CB<3>")
		)
		(pad "244" smd rect
			(at 2.050034 25.925018 90)
			(size 0.519938 1.4986)
			(layers "F.Cu" "F.Mask" "F.Paste")
			(net "GND")
		)
		(pad "245" smd rect
			(at 2.050034 26.774902 90)
			(size 0.519938 1.4986)
			(layers "F.Cu" "F.Mask" "F.Paste")
			(net "M_L_CPU0_SB_DQ<2>")
		)
		(pad "246" smd rect
			(at 2.050034 27.62504 90)
			(size 0.519938 1.4986)
			(layers "F.Cu" "F.Mask" "F.Paste")
			(net "GND")
		)
		(pad "247" smd rect
			(at 2.050034 28.474924 90)
			(size 0.519938 1.4986)
			(layers "F.Cu" "F.Mask" "F.Paste")
			(net "M_L_CPU0_SB_DQ<3>")
		)
		(pad "248" smd rect
			(at 2.050034 29.325062 90)
			(size 0.519938 1.4986)
			(layers "F.Cu" "F.Mask" "F.Paste")
			(net "GND")
		)
		(pad "249" smd rect
			(at 2.050034 30.174946 90)
			(size 0.519938 1.4986)
			(layers "F.Cu" "F.Mask" "F.Paste")
			(net "M_L_CPU0_SB_DQS_DN<5>")
		)
		(pad "250" smd rect
			(at 2.050034 31.025084 90)
			(size 0.519938 1.4986)
			(layers "F.Cu" "F.Mask" "F.Paste")
			(net "M_L_CPU0_SB_DQS_DP<5>")
		)
		(pad "251" smd rect
			(at 2.050034 31.874968 90)
			(size 0.519938 1.4986)
			(layers "F.Cu" "F.Mask" "F.Paste")
			(net "GND")
		)
		(pad "252" smd rect
			(at 2.050034 32.725106 90)
			(size 0.519938 1.4986)
			(layers "F.Cu" "F.Mask" "F.Paste")
			(net "M_L_CPU0_SB_DQ<6>")
		)
		(pad "253" smd rect
			(at 2.050034 33.57499 90)
			(size 0.519938 1.4986)
			(layers "F.Cu" "F.Mask" "F.Paste")
			(net "GND")
		)
		(pad "254" smd rect
			(at 2.050034 34.425128 90)
			(size 0.519938 1.4986)
			(layers "F.Cu" "F.Mask" "F.Paste")
			(net "M_L_CPU0_SB_DQ<7>")
		)
		(pad "255" smd rect
			(at 2.050034 35.275012 90)
			(size 0.519938 1.4986)
			(layers "F.Cu" "F.Mask" "F.Paste")
			(net "GND")
		)
		(pad "256" smd rect
			(at 2.050034 36.124896 90)
			(size 0.519938 1.4986)
			(layers "F.Cu" "F.Mask" "F.Paste")
			(net "M_L_CPU0_SB_DQ<10>")
		)
		(pad "257" smd rect
			(at 2.050034 36.975034 90)
			(size 0.519938 1.4986)
			(layers "F.Cu" "F.Mask" "F.Paste")
			(net "GND")
		)
		(pad "258" smd rect
			(at 2.050034 37.824918 90)
			(size 0.519938 1.4986)
			(layers "F.Cu" "F.Mask" "F.Paste")
			(net "M_L_CPU0_SB_DQ<11>")
		)
		(pad "259" smd rect
			(at 2.050034 38.675056 90)
			(size 0.519938 1.4986)
			(layers "F.Cu" "F.Mask" "F.Paste")
			(net "GND")
		)
		(pad "260" smd rect
			(at 2.050034 39.52494 90)
			(size 0.519938 1.4986)
			(layers "F.Cu" "F.Mask" "F.Paste")
			(net "M_L_CPU0_SB_DQS_DN<6>")
		)
		(pad "261" smd rect
			(at 2.050034 40.375078 90)
			(size 0.519938 1.4986)
			(layers "F.Cu" "F.Mask" "F.Paste")
			(net "M_L_CPU0_SB_DQS_DP<6>")
		)
		(pad "262" smd rect
			(at 2.050034 41.224962 90)
			(size 0.519938 1.4986)
			(layers "F.Cu" "F.Mask" "F.Paste")
			(net "GND")
		)
		(pad "263" smd rect
			(at 2.050034 42.0751 90)
			(size 0.519938 1.4986)
			(layers "F.Cu" "F.Mask" "F.Paste")
			(net "M_L_CPU0_SB_DQ<14>")
		)
		(pad "264" smd rect
			(at 2.050034 42.924984 90)
			(size 0.519938 1.4986)
			(layers "F.Cu" "F.Mask" "F.Paste")
			(net "GND")
		)
		(pad "265" smd rect
			(at 2.050034 43.775122 90)
			(size 0.519938 1.4986)
			(layers "F.Cu" "F.Mask" "F.Paste")
			(net "M_L_CPU0_SB_DQ<15>")
		)
		(pad "266" smd rect
			(at 2.050034 44.625006 90)
			(size 0.519938 1.4986)
			(layers "F.Cu" "F.Mask" "F.Paste")
			(net "GND")
		)
		(pad "267" smd rect
			(at 2.050034 45.47489 90)
			(size 0.519938 1.4986)
			(layers "F.Cu" "F.Mask" "F.Paste")
			(net "M_L_CPU0_SB_DQ<18>")
		)
		(pad "268" smd rect
			(at 2.050034 46.325028 90)
			(size 0.519938 1.4986)
			(layers "F.Cu" "F.Mask" "F.Paste")
			(net "GND")
		)
		(pad "269" smd rect
			(at 2.050034 47.174912 90)
			(size 0.519938 1.4986)
			(layers "F.Cu" "F.Mask" "F.Paste")
			(net "M_L_CPU0_SB_DQ<19>")
		)
		(pad "270" smd rect
			(at 2.050034 48.02505 90)
			(size 0.519938 1.4986)
			(layers "F.Cu" "F.Mask" "F.Paste")
			(net "GND")
		)
		(pad "271" smd rect
			(at 2.050034 48.874934 90)
			(size 0.519938 1.4986)
			(layers "F.Cu" "F.Mask" "F.Paste")
			(net "M_L_CPU0_SB_DQS_DN<7>")
		)
		(pad "272" smd rect
			(at 2.050034 49.725072 90)
			(size 0.519938 1.4986)
			(layers "F.Cu" "F.Mask" "F.Paste")
			(net "M_L_CPU0_SB_DQS_DP<7>")
		)
		(pad "273" smd rect
			(at 2.050034 50.574956 90)
			(size 0.519938 1.4986)
			(layers "F.Cu" "F.Mask" "F.Paste")
			(net "GND")
		)
		(pad "274" smd rect
			(at 2.050034 51.425094 90)
			(size 0.519938 1.4986)
			(layers "F.Cu" "F.Mask" "F.Paste")
			(net "M_L_CPU0_SB_DQ<22>")
		)
		(pad "275" smd rect
			(at 2.050034 52.274978 90)
			(size 0.519938 1.4986)
			(layers "F.Cu" "F.Mask" "F.Paste")
			(net "GND")
		)
		(pad "276" smd rect
			(at 2.050034 53.125116 90)
			(size 0.519938 1.4986)
			(layers "F.Cu" "F.Mask" "F.Paste")
			(net "M_L_CPU0_SB_DQ<23>")
		)
	)
)
